# BASEBOARD_FAB2 (Tioga Pass) — schematic netlist excerpt (pin names and nets, part order shuffled) for the footprints in the layout excerpt that follows; sources: Cadence DE-HDL packaged netlist, KiCad conversion of Wiwynn_Tioga_Pass_MB.brd

T1P7  TPAD-DIFF-4P-GP  pkg DISCRET-GB3  page 256
  \1\  = L1_73OHM_6INCH_DP
  \2\  = L1_73OHM_6INCH_DN
  GND1  = GND
  GND2  = GND

R6W40  RES  10.0K 1% CHIP  pkg 0402  page 155 : A = P3V3_STBY ; B = SPA_5V_SIN_SW_D

(kicad_pcb
	(version 20260206)
	(generator "pcbnew")
	(generator_version "10.0")
	(general
		(thickness 1.6)
		(legacy_teardrops no)
	)
	(paper "A4")
	(title_block
		(title "Wiwynn_Tioga_Pass_MB.brd")
		(comment 1 "Tioga Pass / footprints 1738-1739 of 4770")
	)
	(layers
		(0 "F.Cu" signal "TOP")
		(4 "In1.Cu" signal "L2GND")
		(6 "In2.Cu" signal "L3")
		(8 "In3.Cu" signal "L4GND")
		(10 "In4.Cu" signal "L5")
		(12 "In5.Cu" signal "L6GND")
		(14 "In6.Cu" signal "L7VCC")
		(16 "In7.Cu" signal "L8VCC")
		(18 "In8.Cu" signal "L9GND")
		(20 "In9.Cu" signal "L10")
		(22 "In10.Cu" signal "L11GND")
		(24 "In11.Cu" signal "L12")
		(26 "In12.Cu" signal "L13GND")
		(2 "B.Cu" signal "BOTTOM")
		(9 "F.Adhes" user "F.Adhesive")
		(11 "B.Adhes" user "B.Adhesive")
		(13 "F.Paste" user "Package Geometry/Pastemask Top")
		(15 "B.Paste" user "Package Geometry/Pastemask Bottom")
		(5 "F.SilkS" user "Ref Des/Silkscreen Top")
		(7 "B.SilkS" user "Ref Des/Silkscreen Bottom")
		(1 "F.Mask" user "Board Geometry/Soldermask Top")
		(3 "B.Mask" user "Board Geometry/Soldermask Bottom")
		(17 "Dwgs.User" user "User.Drawings")
		(19 "Cmts.User" user "User.Comments")
		(21 "Eco1.User" user "User.Eco1")
		(23 "Eco2.User" user "User.Eco2")
		(25 "Edge.Cuts" user "Board Geometry/Outline")
		(27 "Margin" user)
		(31 "F.CrtYd" user "Package Geometry/Place Bound Top")
		(29 "B.CrtYd" user "Package Geometry/Place Bound Bottom")
		(35 "F.Fab" user "Ref Des/Assembly Top")
		(33 "B.Fab" user "Ref Des/Assembly Bottom")
	)
	(footprint ""
		(layer "F.Cu")
		(at 117.410484 12.014454 -90)
		(property "Reference" "T1P7"
			(at 0 0 270)
			(layer "F.SilkS")
			(hide yes)
			(effects
				(font
					(size 1.27 1.27)
				)
			)
		)
		(property "Value" "*"
			(at -3.302 1.12395 270)
			(unlocked yes)
			(layer "F.Fab")
			(hide yes)
			(effects
				(font
					(size 0.889 0.889)
					(thickness 0.1524)
				)
			)
		)
		(property "Device Type" "TPAD-DIFF-4P-GP_DISCRET-GB3-TPA"
			(at -3.302 -0.40005 270)
			(unlocked yes)
			(layer "F.Fab")
			(hide yes)
			(effects
				(font
					(size 0.889 0.889)
					(thickness 0.1524)
				)
			)
		)
		(duplicate_pad_numbers_are_jumpers no)
		(fp_line
			(start -2.286 2.286)
			(end 2.286 2.286)
			(stroke
				(width 0.1524)
				(type default)
			)
			(layer "F.SilkS")
		)
		(fp_line
			(start 2.286 2.286)
			(end 2.286 -2.286)
			(stroke
				(width 0.1524)
				(type default)
			)
			(layer "F.SilkS")
		)
		(fp_line
			(start -2.286 -2.286)
			(end -2.286 2.286)
			(stroke
				(width 0.1524)
				(type default)
			)
			(layer "F.SilkS")
		)
		(fp_line
			(start 2.286 -2.286)
			(end -2.286 -2.286)
			(stroke
				(width 0.1524)
				(type default)
			)
			(layer "F.SilkS")
		)
		(fp_line
			(start -2.413 -2.413)
			(end -2.413 -1.143)
			(stroke
				(width 0.4064)
				(type default)
			)
			(layer "F.SilkS")
		)
		(fp_line
			(start -1.143 -2.413)
			(end -2.413 -2.413)
			(stroke
				(width 0.4064)
				(type default)
			)
			(layer "F.SilkS")
		)
		(fp_rect
			(start -2.54 2.54)
			(end 2.54 -2.54)
			(stroke
				(width 0)
				(type default)
			)
			(fill no)
			(layer "F.CrtYd")
		)
		(fp_rect
			(start -2.54 2.54)
			(end 2.54 -2.54)
			(stroke
				(width 0)
				(type default)
			)
			(fill no)
			(layer "F.Fab")
		)
		(pad "1" thru_hole circle
			(at -1.27 -1.27 270)
			(size 1.524 1.524)
			(drill 0.9144)
			(layers "*.Cu" "*.Mask")
			(remove_unused_layers no)
			(net "L1_73OHM_6INCH_DP")
			(clearance -0.0508)
			(thermal_gap 0.127)
			(padstack
				(mode front_inner_back)
				(layer "Inner"
					(shape circle)
					(size 1.1684 1.1684)
					(clearance 0.127)
				)
				(layer "B.Cu"
					(shape circle)
					(size 1.524 1.524)
					(clearance -0.0508)
				)
			)
		)
		(pad "2" thru_hole circle
			(at 1.27 -1.27 270)
			(size 1.524 1.524)
			(drill 0.9144)
			(layers "*.Cu" "*.Mask")
			(remove_unused_layers no)
			(net "L1_73OHM_6INCH_DN")
			(clearance -0.0508)
			(thermal_gap 0.127)
			(padstack
				(mode front_inner_back)
				(layer "Inner"
					(shape circle)
					(size 1.1684 1.1684)
					(clearance 0.127)
				)
				(layer "B.Cu"
					(shape circle)
					(size 1.524 1.524)
					(clearance -0.0508)
				)
			)
		)
		(pad "GND1" thru_hole rect
			(at -1.27 1.27 270)
			(size 1.524 1.524)
			(drill 0.9144)
			(layers "*.Cu" "*.Mask")
			(remove_unused_layers no)
			(net "GND")
			(clearance -0.0508)
			(thermal_gap 0.127)
			(padstack
				(mode front_inner_back)
				(layer "Inner"
					(shape circle)
					(size 1.1684 1.1684)
					(clearance 0.127)
				)
				(layer "B.Cu"
					(shape rect)
					(size 1.524 1.524)
					(clearance -0.0508)
				)
			)
		)
		(pad "GND2" thru_hole rect
			(at 1.27 1.27 270)
			(size 1.524 1.524)
			(drill 0.9144)
			(layers "*.Cu" "*.Mask")
			(remove_unused_layers no)
			(net "GND")
			(clearance -0.0508)
			(thermal_gap 0.127)
			(padstack
				(mode front_inner_back)
				(layer "Inner"
					(shape circle)
					(size 1.1684 1.1684)
					(clearance 0.127)
				)
				(layer "B.Cu"
					(shape rect)
					(size 1.524 1.524)
					(clearance -0.0508)
				)
			)
		)
	)
	(footprint ""
		(layer "F.Cu")
		(at 489.2294 -149.8854 90)
		(property "Reference" "R6W40"
			(at -0.8382 -0.67818 90)
			(unlocked yes)
			(layer "F.SilkS")
			(effects
				(font
					(size 0.4064 0.254)
					(thickness 0.1524)
				)
				(justify left)
			)
		)
		(property "Value" ""
			(at 0 0 90)
			(layer "F.Fab")
			(effects
				(font
					(size 1.27 1.27)
				)
			)
		)
		(duplicate_pad_numbers_are_jumpers no)
		(fp_poly
			(pts
				(xy -0.2794 -0.1016) (xy 0.2794 -0.1016) (xy 0.2794 0.9906) (xy -0.2794 0.9906)
			)
			(stroke
				(width 0)
				(type default)
			)
			(fill no)
			(layer "F.CrtYd")
		)
		(fp_line
			(start 0.2794 -0.1016)
			(end -0.2794 -0.1016)
			(stroke
				(width 0.1)
				(type default)
			)
			(layer "F.Fab")
		)
		(fp_line
			(start -0.2794 -0.1016)
			(end -0.2794 0.9906)
			(stroke
				(width 0.1)
				(type default)
			)
			(layer "F.Fab")
		)
		(fp_line
			(start 0.2794 0.9906)
			(end 0.2794 -0.1016)
			(stroke
				(width 0.1)
				(type default)
			)
			(layer "F.Fab")
		)
		(fp_line
			(start -0.2794 0.9906)
			(end 0.2794 0.9906)
			(stroke
				(width 0.1)
				(type default)
			)
			(layer "F.Fab")
		)
		(pad "1" smd rect
			(at 0 0 90)
			(size 0.508 0.508)
			(layers "F.Cu" "F.Mask" "F.Paste")
			(net "P3V3_STBY")
		)
		(pad "2" smd rect
			(at 0 0.889 90)
			(size 0.508 0.508)
			(layers "F.Cu" "F.Mask" "F.Paste")
			(net "SPA_5V_SIN_SW_D")
		)
		(zone
			(layer "F.Cu")
			(hatch none 0.5)
			(connect_pads
				(clearance 0)
			)
			(min_thickness 0.25)
			(keepout
				(tracks allowed)
				(vias not_allowed)
				(pads allowed)
				(copperpour not_allowed)
				(footprints allowed)
			)
			(placement
				(enabled no)
				(sheetname "")
			)
			(fill
				(thermal_gap 0.5)
				(thermal_bridge_width 0.5)
				(island_removal_mode 0)
			)
			(polygon
				(pts
					(xy 489.4834 -149.6314) (xy 489.4834 -150.1394) (xy 489.8644 -150.1394) (xy 489.8644 -149.6314)
				)
			)
		)
		(zone
			(layer "F.Cu")
			(hatch none 0.5)
			(connect_pads
				(clearance 0)
			)
			(min_thickness 0.25)
			(keepout
				(tracks not_allowed)
				(vias allowed)
				(pads allowed)
				(copperpour not_allowed)
				(footprints allowed)
			)
			(placement
				(enabled no)
				(sheetname "")
			)
			(fill
				(thermal_gap 0.5)
				(thermal_bridge_width 0.5)
				(island_removal_mode 0)
			)
			(polygon
				(pts
					(xy 489.8644 -149.6314) (xy 489.8644 -150.1394) (xy 489.4834 -150.1394) (xy 489.4834 -149.6314)
				)
			)
		)
	)
)
